# T6G (Grand Teton) — schematic parts with pin connectivity, parts 8081–8081 of 8303; source: Cadence DE-HDL packaged netlist (pstxprt.dat, pstxnet.dat, pstchip.dat)

U25  GENOA_SP5  SOCKET6096_13568-001 IO  pkg SOCKET6096_93-4X120-45XA  page 10  (pins 1-336 of 6096)
  A3  VSS_A3  POWER  = GND
  A4  \i3c3_scl||i2c3_scl||spd3_scl||agpio151\  BI  = SMB_CPU0_3_R_SCL
  A5  \i3c1_sda||i2c1_sda||spd1_sda||agpio148\  BI  = I3C_1_SPD_DDRGL_CPU0_R_SDA
  A7  GPP_CLK01N  OUT  = CLK_100M_CPU0_CLK01_R_DN
  A8  GPP_CLK01P  OUT  = CLK_100M_CPU0_CLK01_R_DP
  A9  VSS_A9  POWER  = GND
  A10  GPP_CLK03P  OUT  = CLK_100M_CPU0_CLK03_R_DP
  A11  GPP_CLK03N  OUT  = CLK_100M_CPU0_CLK03_R_DN
  A13  \agpio258||sgpio2_clk||clk_req02_l\  BI  = FAB_REV_ID2
  A14  \agpio256||sgpio0_clk\  BI  = FAB_REV_ID0
  A15  VSS_A15  POWER  = GND
  A16  TMS  IN  = JTAG_CPU0_TMS
  A17  TRST_L  IN  = JTAG_CPU0_TRST_N
  A19  \refclk100ssc_p||gpp_clk10p\  BI  = CLK_100M_REF_OUT_DP
  A20  \refclk100ssc_n||gpp_clk10n\  BI  = CLK_100M_REF_OUT_DN
  A21  VSS_A21  POWER  = GND
  A22  SVD0  BI  = SVID_PVDDCR_CPU0_P0_SVD
  A23  SVC0  OUT  = SVID_PVDDCR_CPU0_P0_SVC
  A25  USB00_DN  BI  = USB2_CPU0_P0_DN
  A26  USB00_DP  BI  = USB2_CPU0_P0_DP
  A27  VSS_A27  POWER  = GND
  A28  USB01_DP  BI  = USB2_CPU0_P1_DP
  A29  USB01_DN  BI  = USB2_CPU0_P1_DN
  A31  RSVD_A31  TRI  = NC
  A32  \az_sdout||sw_mdata2\  OUT  = NC_CPU0_AZ_SDOUT
  A33  \az_sdin2||sw_mdata0\  OUT  = NC_CPU0_AZ_SDIN2
  A34  \az_rst_l||sw_mdata1\  OUT  = NC_CPU0_AZ_RST_N
  A35  RSVD_A35  TRI  = NC
  A41  RSVD_A41  TRI  = NC
  A42  RSVD_A42  TRI  = NC
  A43  VSS_A43  POWER  = GND
  A44  VSS_A44  POWER  = GND
  A45  RSVD_A45  TRI  = NC
  A47  VSS_A47  POWER  = GND
  A48  RSVD_A48  TRI  = NC
  A49  VSS_A49  POWER  = GND
  A50  RSVD_A50  TRI  = NC
  A51  RSVD_A51  TRI  = NC
  A53  VSS_A53  POWER  = GND
  A54  RSVD_A54  TRI  = NC
  A55  RSVD_A55  TRI  = NC
  A56  RSVD_A56  TRI  = NC
  A57  RSVD_A57  TRI  = NC
  A59  RSVD_A59  TRI  = NC
  A60  RSVD_A60  TRI  = NC
  A61  VSS_A61  POWER  = GND
  A62  BP3  OUT  = CPU0_BP3
  A63  BP2  OUT  = CPU0_BP2
  A65  XTRIG_L7  OUT  = CPU0_XTRIG_R2_L7
  A66  XTRIG_L6  OUT  = CPU0_XTRIG_R2_L6
  A67  VSS_A67  POWER  = GND
  A68  ALERT_L  OUT  = APML_CPU0_ALERT_N
  A69  PROCHOT_L  IN  = CPU0_PROCHOT_N
  A71  \i3c0_scl||i2c0_scl||spd0_scl||smbus0_scl||agpio145\  BI  = I3C_0_SPD_DDRAF_CPU0_R_SCL
  A72  VSS_A72  POWER  = GND
  A73  VSS_A73  POWER  = GND
  AA1  VSS_AA1  POWER  = GND
  AA2  MGA_DATA20  BI  = M_G_CPU0_SA_DQ<20>
  AA3  MGA_DQS_H7  BI  = M_G_CPU0_SA_DQS_DP<7>
  AA4  VSS_AA4  POWER  = GND
  AA5  MKA_DATA20  BI  = M_K_CPU0_SA_DQ<20>
  AA6  VSS_AA6  POWER  = GND
  AA7  MKA_DQS_H7  BI  = M_K_CPU0_SA_DQS_DP<7>
  AA8  VSS_AA8  POWER  = GND
  AA9  MLA_DATA20  BI  = M_L_CPU0_SA_DQ<20>
  AA10  MLA_DQS_H7  BI  = M_L_CPU0_SA_DQS_DP<7>
  AA11  VSS_AA11  POWER  = GND
  AA12  MHA_DATA20  BI  = M_H_CPU0_SA_DQ<20>
  AA13  VSS_AA13  POWER  = GND
  AA14  MHA_DQS_H7  BI  = M_H_CPU0_SA_DQS_DP<7>
  AA15  VSS_AA15  POWER  = GND
  AA16  MJA_DATA20  BI  = M_J_CPU0_SA_DQ<20>
  AA17  MJA_DQS_H7  BI  = M_J_CPU0_SA_DQS_DP<7>
  AA18  VSS_AA18  POWER  = GND
  AA19  MIA_DATA20  BI  = M_I_CPU0_SA_DQ<20>
  AA20  VSS_AA20  POWER  = GND
  AA21  MIA_DQS_H7  BI  = M_I_CPU0_SA_DQS_DP<7>
  AA22  VDDCR_SOC_AA22  POWER  = PVDDCR_SOC_P0
  AA23  TEST6_X3D4  OUT  = TP_CPU0_TEST6_X3D4
  AA24  TEST5_IOD  TRI  = TP_CPU0_TEST5_IOD
  AA25  TEST4_IOD  TRI  = TP_CPU0_TEST4_IOD
  AA26  TEST5_CCD7  TRI  = TP_CPU0_TEST5_CCD7
  AA27  TEST4_CCD7  TRI  = TP_CPU0_TEST4_CCD7
  AA28  TEST4_CCD11  TRI  = TP_CPU0_TEST4_CCD11
  AA29  TEST6_X3D2  OUT  = TP_CPU0_TEST6_X3D2
  AA30  TEST4_CCD3  TRI  = TP_CPU0_TEST4_CCD3
  AA31  VSS_AA31  POWER  = GND
  AA32  G2_RXN11  IN  = GMI_CPU1_G0_CPU0_G2_TX_DN<11>
  AA33  G2_RXP11  IN  = GMI_CPU1_G0_CPU0_G2_TX_DP<11>
  AA34  VSS_AA34  POWER  = GND
  AA35  VSS_AA35  POWER  = GND
  AA36  VSS_AA36  POWER  = GND
  AA40  VSS_AA40  POWER  = GND
  AA41  VSS_AA41  POWER  = GND
  AA42  VSS_AA42  POWER  = GND
  AA43  G0_TXP4  OUT  = GMI_CPU0_G0_CPU1_G2_TX_DP<4>
  AA44  G0_TXN4  OUT  = GMI_CPU0_G0_CPU1_G2_TX_DN<4>
  AA45  VSS_AA45  POWER  = GND
  AA46  TEST6_CCD0  OUT  = TP_CPU0_TEST6_CCD0
  AA47  TEST6_X3D0  OUT  = TP_CPU0_TEST6_X3D0
  AA48  TEST4_CCD8  TRI  = TP_CPU0_TEST4_CCD8
  AA49  TEST6_IOD  OUT  = TP_CPU0_TEST6_IOD
  AA50  TEST4_CCD0  TRI  = TP_CPU0_TEST4_CCD0
  AA51  TEST5_CCD0  TRI  = TP_CPU0_TEST5_CCD0
  AA52  TEST4_CCD4  TRI  = TP_CPU0_TEST4_CCD4
  AA53  TEST5_CCD4  TRI  = TP_CPU0_TEST5_CCD4
  AA54  VDDIO_AA54  POWER  = PVDDIO_P0
  AA55  MCA_DQS_H7  BI  = M_C_CPU0_SA_DQS_DP<7>
  AA56  VSS_AA56  POWER  = GND
  AA57  MCA_DATA20  BI  = M_C_CPU0_SA_DQ<20>
  AA58  VSS_AA58  POWER  = GND
  AA59  MDA_DQS_H7  BI  = M_D_CPU0_SA_DQS_DP<7>
  AA60  MDA_DATA20  BI  = M_D_CPU0_SA_DQ<20>
  AA61  VSS_AA61  POWER  = GND
  AA62  MBA_DQS_H7  BI  = M_B_CPU0_SA_DQS_DP<7>
  AA63  VSS_AA63  POWER  = GND
  AA64  MBA_DATA20  BI  = M_B_CPU0_SA_DQ<20>
  AA65  VSS_AA65  POWER  = GND
  AA66  MFA_DQS_H7  BI  = M_F_CPU0_SA_DQS_DP<7>
  AA67  MFA_DATA20  BI  = M_F_CPU0_SA_DQ<20>
  AA68  VSS_AA68  POWER  = GND
  AA69  MEA_DQS_H7  BI  = M_E_CPU0_SA_DQS_DP<7>
  AA70  VSS_AA70  POWER  = GND
  AA71  MEA_DATA20  BI  = M_E_CPU0_SA_DQ<20>
  AA72  VSS_AA72  POWER  = GND
  AA73  MAA_DQS_H7  BI  = M_A_CPU0_SA_DQS_DP<7>
  AA74  MAA_DATA20  BI  = M_A_CPU0_SA_DQ<20>
  AA75  VSS_AA75  POWER  = GND
  AB2  MGA_DATA22  BI  = M_G_CPU0_SA_DQ<22>
  AB3  VSS_AB3  POWER  = GND
  AB4  MGA_DATA21  BI  = M_G_CPU0_SA_DQ<21>
  AB5  VSS_AB5  POWER  = GND
  AB6  MKA_DATA22  BI  = M_K_CPU0_SA_DQ<22>
  AB7  MKA_DATA21  BI  = M_K_CPU0_SA_DQ<21>
  AB8  VSS_AB8  POWER  = GND
  AB9  MLA_DATA22  BI  = M_L_CPU0_SA_DQ<22>
  AB10  VSS_AB10  POWER  = GND
  AB11  MLA_DATA21  BI  = M_L_CPU0_SA_DQ<21>
  AB12  VSS_AB12  POWER  = GND
  AB13  MHA_DATA22  BI  = M_H_CPU0_SA_DQ<22>
  AB14  MHA_DATA21  BI  = M_H_CPU0_SA_DQ<21>
  AB15  VSS_AB15  POWER  = GND
  AB16  MJA_DATA22  BI  = M_J_CPU0_SA_DQ<22>
  AB17  VSS_AB17  POWER  = GND
  AB18  MJA_DATA21  BI  = M_J_CPU0_SA_DQ<21>
  AB19  VSS_AB19  POWER  = GND
  AB20  MIA_DATA22  BI  = M_I_CPU0_SA_DQ<22>
  AB21  MIA_DATA21  BI  = M_I_CPU0_SA_DQ<21>
  AB22  VSS_AB22  POWER  = GND
  AB23  VDDCR_CPU0_AB23  POWER  = PVDDCR_CPU0_P0
  AB24  VDDCR_CPU0_AB24  POWER  = PVDDCR_CPU0_P0
  AB25  VSS_AB25  POWER  = GND
  AB26  VDDCR_CPU0_AB26  POWER  = PVDDCR_CPU0_P0
  AB27  VDDCR_CPU0_AB27  POWER  = PVDDCR_CPU0_P0
  AB28  VSS_AB28  POWER  = GND
  AB29  VDDCR_CPU0_AB29  POWER  = PVDDCR_CPU0_P0
  AB30  VDDCR_CPU0_AB30  POWER  = PVDDCR_CPU0_P0
  AB31  VSS_AB31  POWER  = GND
  AB32  VDDCR_CPU0_AB32  POWER  = PVDDCR_CPU0_P0
  AB33  VDDCR_CPU0_AB33  POWER  = PVDDCR_CPU0_P0
  AB34  VSS_AB34  POWER  = GND
  AB35  G2_RXN13  IN  = GMI_CPU1_G0_CPU0_G2_TX_DN<13>
  AB36  G2_RXP13  IN  = GMI_CPU1_G0_CPU0_G2_TX_DP<13>
  AB37  VSS_AB37  POWER  = GND
  AB39  VSS_AB39  POWER  = GND
  AB40  G0_TXP2  OUT  = GMI_CPU0_G0_CPU1_G2_TX_DP<2>
  AB41  G0_TXN2  OUT  = GMI_CPU0_G0_CPU1_G2_TX_DN<2>
  AB42  VSS_AB42  POWER  = GND
  AB43  VDDCR_CPU0_AB43  POWER  = PVDDCR_CPU0_P0
  AB44  VDDCR_CPU0_AB44  POWER  = PVDDCR_CPU0_P0
  AB45  VSS_AB45  POWER  = GND
  AB46  VDDCR_CPU0_AB46  POWER  = PVDDCR_CPU0_P0
  AB47  VDDCR_CPU0_AB47  POWER  = PVDDCR_CPU0_P0
  AB48  VSS_AB48  POWER  = GND
  AB49  VDDCR_CPU0_AB49  POWER  = PVDDCR_CPU0_P0
  AB50  VDDCR_CPU0_AB50  POWER  = PVDDCR_CPU0_P0
  AB51  VSS_AB51  POWER  = GND
  AB52  VDDCR_CPU0_AB52  POWER  = PVDDCR_CPU0_P0
  AB53  VDDCR_CPU0_AB53  POWER  = PVDDCR_CPU0_P0
  AB54  VSS_AB54  POWER  = GND
  AB55  MCA_DATA21  BI  = M_C_CPU0_SA_DQ<21>
  AB56  MCA_DATA22  BI  = M_C_CPU0_SA_DQ<22>
  AB57  VSS_AB57  POWER  = GND
  AB58  MDA_DATA21  BI  = M_D_CPU0_SA_DQ<21>
  AB59  VSS_AB59  POWER  = GND
  AB60  MDA_DATA22  BI  = M_D_CPU0_SA_DQ<22>
  AB61  VSS_AB61  POWER  = GND
  AB62  MBA_DATA21  BI  = M_B_CPU0_SA_DQ<21>
  AB63  MBA_DATA22  BI  = M_B_CPU0_SA_DQ<22>
  AB64  VSS_AB64  POWER  = GND
  AB65  MFA_DATA21  BI  = M_F_CPU0_SA_DQ<21>
  AB66  VSS_AB66  POWER  = GND
  AB67  MFA_DATA22  BI  = M_F_CPU0_SA_DQ<22>
  AB68  VSS_AB68  POWER  = GND
  AB69  MEA_DATA21  BI  = M_E_CPU0_SA_DQ<21>
  AB70  MEA_DATA22  BI  = M_E_CPU0_SA_DQ<22>
  AB71  VSS_AB71  POWER  = GND
  AB72  MAA_DATA21  BI  = M_A_CPU0_SA_DQ<21>
  AB73  VSS_AB73  POWER  = GND
  AB74  MAA_DATA22  BI  = M_A_CPU0_SA_DQ<22>
  AC1  VSS_AC1  POWER  = GND
  AC2  MGA_DATA24  BI  = M_G_CPU0_SA_DQ<24>
  AC3  MGA_DATA23  BI  = M_G_CPU0_SA_DQ<23>
  AC4  VDDCR_SOC_AC4  POWER  = PVDDCR_SOC_P0
  AC5  MKA_DATA24  BI  = M_K_CPU0_SA_DQ<24>
  AC6  VSS_AC6  POWER  = GND
  AC7  MKA_DATA23  BI  = M_K_CPU0_SA_DQ<23>
  AC8  VSS_AC8  POWER  = GND
  AC9  MLA_DATA24  BI  = M_L_CPU0_SA_DQ<24>
  AC10  MLA_DATA23  BI  = M_L_CPU0_SA_DQ<23>
  AC11  VDDCR_SOC_AC11  POWER  = PVDDCR_SOC_P0
  AC12  MHA_DATA24  BI  = M_H_CPU0_SA_DQ<24>
  AC13  VSS_AC13  POWER  = GND
  AC14  MHA_DATA23  BI  = M_H_CPU0_SA_DQ<23>
  AC15  VSS_AC15  POWER  = GND
  AC16  MJA_DATA24  BI  = M_J_CPU0_SA_DQ<24>
  AC17  MJA_DATA23  BI  = M_J_CPU0_SA_DQ<23>
  AC18  VDDCR_SOC_AC18  POWER  = PVDDCR_SOC_P0
  AC19  MIA_DATA24  BI  = M_I_CPU0_SA_DQ<24>
  AC20  VSS_AC20  POWER  = GND
  AC21  MIA_DATA23  BI  = M_I_CPU0_SA_DQ<23>
  AC22  VSS_AC22  POWER  = GND
  AC23  G2_RXN1  IN  = GMI_CPU1_G0_CPU0_G2_TX_DN<1>
  AC24  G2_RXP1  IN  = GMI_CPU1_G0_CPU0_G2_TX_DP<1>
  AC25  VSS_AC25  POWER  = GND
  AC26  G2_RXN4  IN  = GMI_CPU1_G0_CPU0_G2_TX_DN<4>
  AC27  G2_RXP4  IN  = GMI_CPU1_G0_CPU0_G2_TX_DP<4>
  AC28  VSS_AC28  POWER  = GND
  AC29  G2_RXN7  IN  = GMI_CPU1_G0_CPU0_G2_TX_DN<7>
  AC30  G2_RXP7  IN  = GMI_CPU1_G0_CPU0_G2_TX_DP<7>
  AC31  VSS_AC31  POWER  = GND
  AC32  G2_RXN10  IN  = GMI_CPU1_G0_CPU0_G2_TX_DN<10>
  AC33  G2_RXP10  IN  = GMI_CPU1_G0_CPU0_G2_TX_DP<10>
  AC34  VSS_AC34  POWER  = GND
  AC35  VDDCR_CPU0_AC35  POWER  = PVDDCR_CPU0_P0
  AC36  VDDCR_CPU0_AC36  POWER  = PVDDCR_CPU0_P0
  AC40  VDDCR_CPU0_AC40  POWER  = PVDDCR_CPU0_P0
  AC41  VDDCR_CPU0_AC41  POWER  = PVDDCR_CPU0_P0
  AC42  VSS_AC42  POWER  = GND
  AC43  G0_TXP5  OUT  = GMI_CPU0_G0_CPU1_G2_TX_DP<5>
  AC44  G0_TXN5  OUT  = GMI_CPU0_G0_CPU1_G2_TX_DN<5>
  AC45  VSS_AC45  POWER  = GND
  AC46  G0_TXP8  OUT  = GMI_CPU0_G0_CPU1_G2_TX_DP<8>
  AC47  G0_TXN8  OUT  = GMI_CPU0_G0_CPU1_G2_TX_DN<8>
  AC48  VSS_AC48  POWER  = GND
  AC49  G0_TXP11  OUT  = GMI_CPU0_G0_CPU1_G2_TX_DP<11>
  AC50  G0_TXN11  OUT  = GMI_CPU0_G0_CPU1_G2_TX_DN<11>
  AC51  VSS_AC51  POWER  = GND
  AC52  G0_TXP14  OUT  = GMI_CPU0_G0_CPU1_G2_TX_DP<14>
  AC53  G0_TXN14  OUT  = GMI_CPU0_G0_CPU1_G2_TX_DN<14>
  AC54  VSS_AC54  POWER  = GND
  AC55  MCA_DATA23  BI  = M_C_CPU0_SA_DQ<23>
  AC56  VSS_AC56  POWER  = GND
  AC57  MCA_DATA24  BI  = M_C_CPU0_SA_DQ<24>
  AC58  VDDIO_AC58  POWER  = PVDDIO_P0
  AC59  MDA_DATA23  BI  = M_D_CPU0_SA_DQ<23>
  AC60  MDA_DATA24  BI  = M_D_CPU0_SA_DQ<24>
  AC61  VSS_AC61  POWER  = GND
  AC62  MBA_DATA23  BI  = M_B_CPU0_SA_DQ<23>
  AC63  VSS_AC63  POWER  = GND
  AC64  MBA_DATA24  BI  = M_B_CPU0_SA_DQ<24>
  AC65  VDDIO_AC65  POWER  = PVDDIO_P0
  AC66  MFA_DATA23  BI  = M_F_CPU0_SA_DQ<23>
  AC67  MFA_DATA24  BI  = M_F_CPU0_SA_DQ<24>
  AC68  VSS_AC68  POWER  = GND
  AC69  MEA_DATA23  BI  = M_E_CPU0_SA_DQ<23>
  AC70  VSS_AC70  POWER  = GND
  AC71  MEA_DATA24  BI  = M_E_CPU0_SA_DQ<24>
  AC72  VDDIO_AC72  POWER  = PVDDIO_P0
  AC73  MAA_DATA23  BI  = M_A_CPU0_SA_DQ<23>
  AC74  MAA_DATA24  BI  = M_A_CPU0_SA_DQ<24>
  AC75  VSS_AC75  POWER  = GND
  AD2  MGA_DATA26  BI  = M_G_CPU0_SA_DQ<26>
  AD3  VSS_AD3  POWER  = GND
  AD4  MGA_DATA25  BI  = M_G_CPU0_SA_DQ<25>
  AD5  VSS_AD5  POWER  = GND
  AD6  MKA_DATA26  BI  = M_K_CPU0_SA_DQ<26>
  AD7  MKA_DATA25  BI  = M_K_CPU0_SA_DQ<25>
  AD8  VSS_AD8  POWER  = GND
  AD9  MLA_DATA26  BI  = M_L_CPU0_SA_DQ<26>
  AD10  VSS_AD10  POWER  = GND
  AD11  MLA_DATA25  BI  = M_L_CPU0_SA_DQ<25>
  AD12  VSS_AD12  POWER  = GND
  AD13  MHA_DATA26  BI  = M_H_CPU0_SA_DQ<26>
  AD14  MHA_DATA25  BI  = M_H_CPU0_SA_DQ<25>
  AD15  VSS_AD15  POWER  = GND
  AD16  MJA_DATA26  BI  = M_J_CPU0_SA_DQ<26>
  AD17  VSS_AD17  POWER  = GND
  AD18  MJA_DATA25  BI  = M_J_CPU0_SA_DQ<25>
  AD19  VSS_AD19  POWER  = GND
  AD20  MIA_DATA26  BI  = M_I_CPU0_SA_DQ<26>
  AD21  MIA_DATA25  BI  = M_I_CPU0_SA_DQ<25>
  AD22  VDDCR_SOC_AD22  POWER  = PVDDCR_SOC_P0
  AD23  VSS_AD23  POWER  = GND
  AD24  VSS_AD24  POWER  = GND
  AD25  VSS_AD25  POWER  = GND
  AD26  VSS_AD26  POWER  = GND
  AD27  VSS_AD27  POWER  = GND
  AD28  VSS_AD28  POWER  = GND
  AD29  VSS_AD29  POWER  = GND
  AD30  VSS_AD30  POWER  = GND
  AD31  VSS_AD31  POWER  = GND
  AD32  VSS_AD32  POWER  = GND
  AD33  VSS_AD33  POWER  = GND
  AD34  VSS_AD34  POWER  = GND
  AD35  G2_RXN14  IN  = GMI_CPU1_G0_CPU0_G2_TX_DN<14>
  AD36  G2_RXP14  IN  = GMI_CPU1_G0_CPU0_G2_TX_DP<14>
  AD37  VSS_AD37  POWER  = GND
  AD39  VSS_AD39  POWER  = GND
  AD40  G0_TXP1  OUT  = GMI_CPU0_G0_CPU1_G2_TX_DP<1>
  AD41  G0_TXN1  OUT  = GMI_CPU0_G0_CPU1_G2_TX_DN<1>
  AD42  VSS_AD42  POWER  = GND
  AD43  VSS_AD43  POWER  = GND
  AD44  VSS_AD44  POWER  = GND
  AD45  VSS_AD45  POWER  = GND
  AD46  VSS_AD46  POWER  = GND
  AD47  VSS_AD47  POWER  = GND
  AD48  VSS_AD48  POWER  = GND
  AD49  VSS_AD49  POWER  = GND
  AD50  VSS_AD50  POWER  = GND
  AD51  VSS_AD51  POWER  = GND
  AD52  VSS_AD52  POWER  = GND
  AD53  VSS_AD53  POWER  = GND
  AD54  VDDIO_AD54  POWER  = PVDDIO_P0
  AD55  MCA_DATA25  BI  = M_C_CPU0_SA_DQ<25>
  AD56  MCA_DATA26  BI  = M_C_CPU0_SA_DQ<26>
  AD57  VSS_AD57  POWER  = GND
  AD58  MDA_DATA25  BI  = M_D_CPU0_SA_DQ<25>
  AD59  VSS_AD59  POWER  = GND
  AD60  MDA_DATA26  BI  = M_D_CPU0_SA_DQ<26>
  AD61  VSS_AD61  POWER  = GND
  AD62  MBA_DATA25  BI  = M_B_CPU0_SA_DQ<25>
  AD63  MBA_DATA26  BI  = M_B_CPU0_SA_DQ<26>
  AD64  VSS_AD64  POWER  = GND
  AD65  MFA_DATA25  BI  = M_F_CPU0_SA_DQ<25>
  AD66  VSS_AD66  POWER  = GND
